(kicad_pcb
	(version 20260206)
	(generator "pcbnew")
	(generator_version "10.0")
	(general
		(thickness 1.6)
		(legacy_teardrops no)
	)
	(paper "A4")
	(title_block
		(title "v2-tray-backplane — ms_tbp_v2.brd")
		(comment 1 "Open CloudServer (Microsoft) / footprint 154 of 164 (J2), pads 1-121 of 162")
	)
	(layers
		(0 "F.Cu" signal "TOP")
		(4 "In1.Cu" signal "LYR2")
		(6 "In2.Cu" signal "LYR3")
		(8 "In3.Cu" signal "LYR4")
		(10 "In4.Cu" signal "LYR5")
		(12 "In5.Cu" signal "LYR6")
		(14 "In6.Cu" signal "LYR7")
		(2 "B.Cu" signal "BOTTOM")
		(9 "F.Adhes" user "F.Adhesive")
		(11 "B.Adhes" user "B.Adhesive")
		(13 "F.Paste" user "Package Geometry/Pastemask Top")
		(15 "B.Paste" user "Package Geometry/Pastemask Bottom")
		(5 "F.SilkS" user "Ref Des/Silkscreen Top")
		(7 "B.SilkS" user "Ref Des/Silkscreen Bottom")
		(1 "F.Mask" user "Board Geometry/Soldermask Top")
		(3 "B.Mask" user "Board Geometry/Soldermask Bottom")
		(17 "Dwgs.User" user "User.Drawings")
		(19 "Cmts.User" user "User.Comments")
		(21 "Eco1.User" user "User.Eco1")
		(23 "Eco2.User" user "User.Eco2")
		(25 "Edge.Cuts" user "Board Geometry/Outline")
		(27 "Margin" user)
		(31 "F.CrtYd" user "Package Geometry/Place Bound Top")
		(29 "B.CrtYd" user "Package Geometry/Place Bound Bottom")
		(35 "F.Fab" user "Ref Des/Assembly Top")
		(33 "B.Fab" user "Ref Des/Assembly Bottom")
	)
	(footprint ""
		(layer "F.Cu")
		(at -375.079999 30.959999 90)
		(property "Reference" "J2"
			(at 17.249079 1.136119 0)
			(unlocked yes)
			(layer "F.SilkS")
			(effects
				(font
					(size 0.762 0.5334)
					(thickness 0.1016)
				)
			)
		)
		(property "Value" ""
			(at 0 0 90)
			(layer "F.Fab")
			(effects
				(font
					(size 1.27 1.27)
				)
			)
		)
		(duplicate_pad_numbers_are_jumpers no)
		(pad "" np_thru_hole circle
			(at -14.4907 -3.048 90)
			(size 0.508 0.508)
			(drill 1.27)
			(layers "*.Cu" "*.Mask")
		)
		(pad "" np_thru_hole circle
			(at 14.4907 0 90)
			(size 0.508 0.508)
			(drill 1.27)
			(layers "*.Cu" "*.Mask")
		)
		(pad "1" smd circle
			(at -12.065 -4.445 90)
			(size 0.635 0.635)
			(layers "F.Cu" "F.Mask" "F.Paste")
			(net "GND")
		)
		(pad "2" smd circle
			(at -12.065 -3.175 90)
			(size 0.635 0.635)
			(layers "F.Cu" "F.Mask" "F.Paste")
			(net "PCIE_T2B_B1_RX_DP<7>")
		)
		(pad "3" smd circle
			(at -12.065 -1.905 90)
			(size 0.635 0.635)
			(layers "F.Cu" "F.Mask" "F.Paste")
			(net "GND")
		)
		(pad "4" smd circle
			(at -12.065 -0.635 90)
			(size 0.635 0.635)
			(layers "F.Cu" "F.Mask" "F.Paste")
			(net "PCIE_T2B_B1_RX_DP<15>")
		)
		(pad "5" smd circle
			(at -12.065 0.635 90)
			(size 0.635 0.635)
			(layers "F.Cu" "F.Mask" "F.Paste")
			(net "GND")
		)
		(pad "6" smd circle
			(at -12.065 1.905 90)
			(size 0.635 0.635)
			(layers "F.Cu" "F.Mask" "F.Paste")
			(net "PCIE_B2T_B1_TX_DP<7>")
		)
		(pad "7" smd circle
			(at -12.065 3.175 90)
			(size 0.635 0.635)
			(layers "F.Cu" "F.Mask" "F.Paste")
			(net "GND")
		)
		(pad "8" smd circle
			(at -12.065 4.445 90)
			(size 0.635 0.635)
			(layers "F.Cu" "F.Mask" "F.Paste")
			(net "PCIE_B2T_B1_TX_DP<15>")
		)
		(pad "9" smd circle
			(at -10.795 -4.445 90)
			(size 0.635 0.635)
			(layers "F.Cu" "F.Mask" "F.Paste")
			(net "GND")
		)
		(pad "10" smd circle
			(at -10.795 -3.175 90)
			(size 0.635 0.635)
			(layers "F.Cu" "F.Mask" "F.Paste")
			(net "PCIE_T2B_B1_RX_DN<7>")
		)
		(pad "11" smd circle
			(at -10.795 -1.905 90)
			(size 0.635 0.635)
			(layers "F.Cu" "F.Mask" "F.Paste")
			(net "GND")
		)
		(pad "12" smd circle
			(at -10.795 -0.635 90)
			(size 0.635 0.635)
			(layers "F.Cu" "F.Mask" "F.Paste")
			(net "PCIE_T2B_B1_RX_DN<15>")
		)
		(pad "13" smd circle
			(at -10.795 0.635 90)
			(size 0.635 0.635)
			(layers "F.Cu" "F.Mask" "F.Paste")
			(net "GND")
		)
		(pad "14" smd circle
			(at -10.795 1.905 90)
			(size 0.635 0.635)
			(layers "F.Cu" "F.Mask" "F.Paste")
			(net "PCIE_B2T_B1_TX_DN<7>")
		)
		(pad "15" smd circle
			(at -10.795 3.175 90)
			(size 0.635 0.635)
			(layers "F.Cu" "F.Mask" "F.Paste")
			(net "GND")
		)
		(pad "16" smd circle
			(at -10.795 4.445 90)
			(size 0.635 0.635)
			(layers "F.Cu" "F.Mask" "F.Paste")
			(net "PCIE_B2T_B1_TX_DN<15>")
		)
		(pad "17" smd circle
			(at -9.525 -4.445 90)
			(size 0.635 0.635)
			(layers "F.Cu" "F.Mask" "F.Paste")
			(net "PCIE_T2B_B1_RX_DP<6>")
		)
		(pad "18" smd circle
			(at -9.525 -3.175 90)
			(size 0.635 0.635)
			(layers "F.Cu" "F.Mask" "F.Paste")
			(net "GND")
		)
		(pad "19" smd circle
			(at -9.525 -1.905 90)
			(size 0.635 0.635)
			(layers "F.Cu" "F.Mask" "F.Paste")
			(net "PCIE_T2B_B1_RX_DP<14>")
		)
		(pad "20" smd circle
			(at -9.525 -0.635 90)
			(size 0.635 0.635)
			(layers "F.Cu" "F.Mask" "F.Paste")
			(net "GND")
		)
		(pad "21" smd circle
			(at -9.525 0.635 90)
			(size 0.635 0.635)
			(layers "F.Cu" "F.Mask" "F.Paste")
			(net "PCIE_B2T_B1_TX_DP<6>")
		)
		(pad "22" smd circle
			(at -9.525 1.905 90)
			(size 0.635 0.635)
			(layers "F.Cu" "F.Mask" "F.Paste")
			(net "GND")
		)
		(pad "23" smd circle
			(at -9.525 3.175 90)
			(size 0.635 0.635)
			(layers "F.Cu" "F.Mask" "F.Paste")
			(net "PCIE_B2T_B1_TX_DP<14>")
		)
		(pad "24" smd circle
			(at -9.525 4.445 90)
			(size 0.635 0.635)
			(layers "F.Cu" "F.Mask" "F.Paste")
			(net "GND")
		)
		(pad "25" smd circle
			(at -8.255 -4.445 90)
			(size 0.635 0.635)
			(layers "F.Cu" "F.Mask" "F.Paste")
			(net "PCIE_T2B_B1_RX_DN<6>")
		)
		(pad "26" smd circle
			(at -8.255 -3.175 90)
			(size 0.635 0.635)
			(layers "F.Cu" "F.Mask" "F.Paste")
			(net "GND")
		)
		(pad "27" smd circle
			(at -8.255 -1.905 90)
			(size 0.635 0.635)
			(layers "F.Cu" "F.Mask" "F.Paste")
			(net "PCIE_T2B_B1_RX_DN<14>")
		)
		(pad "28" smd circle
			(at -8.255 -0.635 90)
			(size 0.635 0.635)
			(layers "F.Cu" "F.Mask" "F.Paste")
			(net "GND")
		)
		(pad "29" smd circle
			(at -8.255 0.635 90)
			(size 0.635 0.635)
			(layers "F.Cu" "F.Mask" "F.Paste")
			(net "PCIE_B2T_B1_TX_DN<6>")
		)
		(pad "30" smd circle
			(at -8.255 1.905 90)
			(size 0.635 0.635)
			(layers "F.Cu" "F.Mask" "F.Paste")
			(net "GND")
		)
		(pad "31" smd circle
			(at -8.255 3.175 90)
			(size 0.635 0.635)
			(layers "F.Cu" "F.Mask" "F.Paste")
			(net "PCIE_B2T_B1_TX_DN<14>")
		)
		(pad "32" smd circle
			(at -8.255 4.445 90)
			(size 0.635 0.635)
			(layers "F.Cu" "F.Mask" "F.Paste")
			(net "GND")
		)
		(pad "33" smd circle
			(at -6.985 -4.445 90)
			(size 0.635 0.635)
			(layers "F.Cu" "F.Mask" "F.Paste")
			(net "GND")
		)
		(pad "34" smd circle
			(at -6.985 -3.175 90)
			(size 0.635 0.635)
			(layers "F.Cu" "F.Mask" "F.Paste")
			(net "PCIE_T2B_B1_RX_DP<5>")
		)
		(pad "35" smd circle
			(at -6.985 -1.905 90)
			(size 0.635 0.635)
			(layers "F.Cu" "F.Mask" "F.Paste")
			(net "GND")
		)
		(pad "36" smd circle
			(at -6.985 -0.635 90)
			(size 0.635 0.635)
			(layers "F.Cu" "F.Mask" "F.Paste")
			(net "PCIE_T2B_B1_RX_DP<13>")
		)
		(pad "37" smd circle
			(at -6.985 0.635 90)
			(size 0.635 0.635)
			(layers "F.Cu" "F.Mask" "F.Paste")
			(net "GND")
		)
		(pad "38" smd circle
			(at -6.985 1.905 90)
			(size 0.635 0.635)
			(layers "F.Cu" "F.Mask" "F.Paste")
			(net "PCIE_B2T_B1_TX_DP<5>")
		)
		(pad "39" smd circle
			(at -6.985 3.175 90)
			(size 0.635 0.635)
			(layers "F.Cu" "F.Mask" "F.Paste")
			(net "GND")
		)
		(pad "40" smd circle
			(at -6.985 4.445 90)
			(size 0.635 0.635)
			(layers "F.Cu" "F.Mask" "F.Paste")
			(net "PCIE_B2T_B1_TX_DP<13>")
		)
		(pad "41" smd circle
			(at -5.715 -4.445 90)
			(size 0.635 0.635)
			(layers "F.Cu" "F.Mask" "F.Paste")
			(net "GND")
		)
		(pad "42" smd circle
			(at -5.715 -3.175 90)
			(size 0.635 0.635)
			(layers "F.Cu" "F.Mask" "F.Paste")
			(net "PCIE_T2B_B1_RX_DN<5>")
		)
		(pad "43" smd circle
			(at -5.715 -1.905 90)
			(size 0.635 0.635)
			(layers "F.Cu" "F.Mask" "F.Paste")
			(net "GND")
		)
		(pad "44" smd circle
			(at -5.715 -0.635 90)
			(size 0.635 0.635)
			(layers "F.Cu" "F.Mask" "F.Paste")
			(net "PCIE_T2B_B1_RX_DN<13>")
		)
		(pad "45" smd circle
			(at -5.715 0.635 90)
			(size 0.635 0.635)
			(layers "F.Cu" "F.Mask" "F.Paste")
			(net "GND")
		)
		(pad "46" smd circle
			(at -5.715 1.905 90)
			(size 0.635 0.635)
			(layers "F.Cu" "F.Mask" "F.Paste")
			(net "PCIE_B2T_B1_TX_DN<5>")
		)
		(pad "47" smd circle
			(at -5.715 3.175 90)
			(size 0.635 0.635)
			(layers "F.Cu" "F.Mask" "F.Paste")
			(net "GND")
		)
		(pad "48" smd circle
			(at -5.715 4.445 90)
			(size 0.635 0.635)
			(layers "F.Cu" "F.Mask" "F.Paste")
			(net "PCIE_B2T_B1_TX_DN<13>")
		)
		(pad "49" smd circle
			(at -4.445 -4.445 90)
			(size 0.635 0.635)
			(layers "F.Cu" "F.Mask" "F.Paste")
			(net "PCIE_T2B_B1_RX_DP<4>")
		)
		(pad "50" smd circle
			(at -4.445 -3.175 90)
			(size 0.635 0.635)
			(layers "F.Cu" "F.Mask" "F.Paste")
			(net "GND")
		)
		(pad "51" smd circle
			(at -4.445 -1.905 90)
			(size 0.635 0.635)
			(layers "F.Cu" "F.Mask" "F.Paste")
			(net "PCIE_T2B_B1_RX_DP<12>")
		)
		(pad "52" smd circle
			(at -4.445 -0.635 90)
			(size 0.635 0.635)
			(layers "F.Cu" "F.Mask" "F.Paste")
			(net "GND")
		)
		(pad "53" smd circle
			(at -4.445 0.635 90)
			(size 0.635 0.635)
			(layers "F.Cu" "F.Mask" "F.Paste")
			(net "PCIE_B2T_B1_TX_DP<4>")
		)
		(pad "54" smd circle
			(at -4.445 1.905 90)
			(size 0.635 0.635)
			(layers "F.Cu" "F.Mask" "F.Paste")
			(net "GND")
		)
		(pad "55" smd circle
			(at -4.445 3.175 90)
			(size 0.635 0.635)
			(layers "F.Cu" "F.Mask" "F.Paste")
			(net "PCIE_B2T_B1_TX_DP<12>")
		)
		(pad "56" smd circle
			(at -4.445 4.445 90)
			(size 0.635 0.635)
			(layers "F.Cu" "F.Mask" "F.Paste")
			(net "GND")
		)
		(pad "57" smd circle
			(at -3.175 -4.445 90)
			(size 0.635 0.635)
			(layers "F.Cu" "F.Mask" "F.Paste")
			(net "PCIE_T2B_B1_RX_DN<4>")
		)
		(pad "58" smd circle
			(at -3.175 -3.175 90)
			(size 0.635 0.635)
			(layers "F.Cu" "F.Mask" "F.Paste")
			(net "GND")
		)
		(pad "59" smd circle
			(at -3.175 -1.905 90)
			(size 0.635 0.635)
			(layers "F.Cu" "F.Mask" "F.Paste")
			(net "PCIE_T2B_B1_RX_DN<12>")
		)
		(pad "60" smd circle
			(at -3.175 -0.635 90)
			(size 0.635 0.635)
			(layers "F.Cu" "F.Mask" "F.Paste")
			(net "GND")
		)
		(pad "61" smd circle
			(at -3.175 0.635 90)
			(size 0.635 0.635)
			(layers "F.Cu" "F.Mask" "F.Paste")
			(net "PCIE_B2T_B1_TX_DN<4>")
		)
		(pad "62" smd circle
			(at -3.175 1.905 90)
			(size 0.635 0.635)
			(layers "F.Cu" "F.Mask" "F.Paste")
			(net "GND")
		)
		(pad "63" smd circle
			(at -3.175 3.175 90)
			(size 0.635 0.635)
			(layers "F.Cu" "F.Mask" "F.Paste")
			(net "PCIE_B2T_B1_TX_DN<12>")
		)
		(pad "64" smd circle
			(at -3.175 4.445 90)
			(size 0.635 0.635)
			(layers "F.Cu" "F.Mask" "F.Paste")
			(net "GND")
		)
		(pad "65" smd circle
			(at -1.905 -4.445 90)
			(size 0.635 0.635)
			(layers "F.Cu" "F.Mask" "F.Paste")
			(net "GND")
		)
		(pad "66" smd circle
			(at -1.905 -3.175 90)
			(size 0.635 0.635)
			(layers "F.Cu" "F.Mask" "F.Paste")
			(net "PCIE_T2B_B1_RX_DP<3>")
		)
		(pad "67" smd circle
			(at -1.905 -1.905 90)
			(size 0.635 0.635)
			(layers "F.Cu" "F.Mask" "F.Paste")
			(net "GND")
		)
		(pad "68" smd circle
			(at -1.905 -0.635 90)
			(size 0.635 0.635)
			(layers "F.Cu" "F.Mask" "F.Paste")
			(net "PCIE_T2B_B1_RX_DP<11>")
		)
		(pad "69" smd circle
			(at -1.905 0.635 90)
			(size 0.635 0.635)
			(layers "F.Cu" "F.Mask" "F.Paste")
			(net "GND")
		)
		(pad "70" smd circle
			(at -1.905 1.905 90)
			(size 0.635 0.635)
			(layers "F.Cu" "F.Mask" "F.Paste")
			(net "PCIE_B2T_B1_TX_DP<3>")
		)
		(pad "71" smd circle
			(at -1.905 3.175 90)
			(size 0.635 0.635)
			(layers "F.Cu" "F.Mask" "F.Paste")
			(net "GND")
		)
		(pad "72" smd circle
			(at -1.905 4.445 90)
			(size 0.635 0.635)
			(layers "F.Cu" "F.Mask" "F.Paste")
			(net "PCIE_B2T_B1_TX_DP<11>")
		)
		(pad "73" smd circle
			(at -0.635 -4.445 90)
			(size 0.635 0.635)
			(layers "F.Cu" "F.Mask" "F.Paste")
			(net "GND")
		)
		(pad "74" smd circle
			(at -0.635 -3.175 90)
			(size 0.635 0.635)
			(layers "F.Cu" "F.Mask" "F.Paste")
			(net "PCIE_T2B_B1_RX_DN<3>")
		)
		(pad "75" smd circle
			(at -0.635 -1.905 90)
			(size 0.635 0.635)
			(layers "F.Cu" "F.Mask" "F.Paste")
			(net "GND")
		)
		(pad "76" smd circle
			(at -0.635 -0.635 90)
			(size 0.635 0.635)
			(layers "F.Cu" "F.Mask" "F.Paste")
			(net "PCIE_T2B_B1_RX_DN<11>")
		)
		(pad "77" smd circle
			(at -0.635 0.635 90)
			(size 0.635 0.635)
			(layers "F.Cu" "F.Mask" "F.Paste")
			(net "GND")
		)
		(pad "78" smd circle
			(at -0.635 1.905 90)
			(size 0.635 0.635)
			(layers "F.Cu" "F.Mask" "F.Paste")
			(net "PCIE_B2T_B1_TX_DN<3>")
		)
		(pad "79" smd circle
			(at -0.635 3.175 90)
			(size 0.635 0.635)
			(layers "F.Cu" "F.Mask" "F.Paste")
			(net "GND")
		)
		(pad "80" smd circle
			(at -0.635 4.445 90)
			(size 0.635 0.635)
			(layers "F.Cu" "F.Mask" "F.Paste")
			(net "PCIE_B2T_B1_TX_DN<11>")
		)
		(pad "81" smd circle
			(at 0.635 -4.445 90)
			(size 0.635 0.635)
			(layers "F.Cu" "F.Mask" "F.Paste")
			(net "PCIE_T2B_B1_RX_DP<2>")
		)
		(pad "82" smd circle
			(at 0.635 -3.175 90)
			(size 0.635 0.635)
			(layers "F.Cu" "F.Mask" "F.Paste")
			(net "GND")
		)
		(pad "83" smd circle
			(at 0.635 -1.905 90)
			(size 0.635 0.635)
			(layers "F.Cu" "F.Mask" "F.Paste")
			(net "PCIE_T2B_B1_RX_DP<10>")
		)
		(pad "84" smd circle
			(at 0.635 -0.635 90)
			(size 0.635 0.635)
			(layers "F.Cu" "F.Mask" "F.Paste")
			(net "GND")
		)
		(pad "85" smd circle
			(at 0.635 0.635 90)
			(size 0.635 0.635)
			(layers "F.Cu" "F.Mask" "F.Paste")
			(net "PCIE_B2T_B1_TX_DP<2>")
		)
		(pad "86" smd circle
			(at 0.635 1.905 90)
			(size 0.635 0.635)
			(layers "F.Cu" "F.Mask" "F.Paste")
			(net "GND")
		)
		(pad "87" smd circle
			(at 0.635 3.175 90)
			(size 0.635 0.635)
			(layers "F.Cu" "F.Mask" "F.Paste")
			(net "PCIE_B2T_B1_TX_DP<10>")
		)
		(pad "88" smd circle
			(at 0.635 4.445 90)
			(size 0.635 0.635)
			(layers "F.Cu" "F.Mask" "F.Paste")
			(net "GND")
		)
		(pad "89" smd circle
			(at 1.905 -4.445 90)
			(size 0.635 0.635)
			(layers "F.Cu" "F.Mask" "F.Paste")
			(net "PCIE_T2B_B1_RX_DN<2>")
		)
		(pad "90" smd circle
			(at 1.905 -3.175 90)
			(size 0.635 0.635)
			(layers "F.Cu" "F.Mask" "F.Paste")
			(net "GND")
		)
		(pad "91" smd circle
			(at 1.905 -1.905 90)
			(size 0.635 0.635)
			(layers "F.Cu" "F.Mask" "F.Paste")
			(net "PCIE_T2B_B1_RX_DN<10>")
		)
		(pad "92" smd circle
			(at 1.905 -0.635 90)
			(size 0.635 0.635)
			(layers "F.Cu" "F.Mask" "F.Paste")
			(net "GND")
		)
		(pad "93" smd circle
			(at 1.905 0.635 90)
			(size 0.635 0.635)
			(layers "F.Cu" "F.Mask" "F.Paste")
			(net "PCIE_B2T_B1_TX_DN<2>")
		)
		(pad "94" smd circle
			(at 1.905 1.905 90)
			(size 0.635 0.635)
			(layers "F.Cu" "F.Mask" "F.Paste")
			(net "GND")
		)
		(pad "95" smd circle
			(at 1.905 3.175 90)
			(size 0.635 0.635)
			(layers "F.Cu" "F.Mask" "F.Paste")
			(net "PCIE_B2T_B1_TX_DN<10>")
		)
		(pad "96" smd circle
			(at 1.905 4.445 90)
			(size 0.635 0.635)
			(layers "F.Cu" "F.Mask" "F.Paste")
			(net "GND")
		)
		(pad "97" smd circle
			(at 3.175 -4.445 90)
			(size 0.635 0.635)
			(layers "F.Cu" "F.Mask" "F.Paste")
			(net "GND")
		)
		(pad "98" smd circle
			(at 3.175 -3.175 90)
			(size 0.635 0.635)
			(layers "F.Cu" "F.Mask" "F.Paste")
			(net "PCIE_T2B_B1_RX_DP<1>")
		)
		(pad "99" smd circle
			(at 3.175 -1.905 90)
			(size 0.635 0.635)
			(layers "F.Cu" "F.Mask" "F.Paste")
			(net "GND")
		)
		(pad "100" smd circle
			(at 3.175 -0.635 90)
			(size 0.635 0.635)
			(layers "F.Cu" "F.Mask" "F.Paste")
			(net "PCIE_T2B_B1_RX_DP<9>")
		)
		(pad "101" smd circle
			(at 3.175 0.635 90)
			(size 0.635 0.635)
			(layers "F.Cu" "F.Mask" "F.Paste")
			(net "GND")
		)
		(pad "102" smd circle
			(at 3.175 1.905 90)
			(size 0.635 0.635)
			(layers "F.Cu" "F.Mask" "F.Paste")
			(net "PCIE_B2T_B1_TX_DP<1>")
		)
		(pad "103" smd circle
			(at 3.175 3.175 90)
			(size 0.635 0.635)
			(layers "F.Cu" "F.Mask" "F.Paste")
			(net "GND")
		)
		(pad "104" smd circle
			(at 3.175 4.445 90)
			(size 0.635 0.635)
			(layers "F.Cu" "F.Mask" "F.Paste")
			(net "PCIE_B2T_B1_TX_DP<9>")
		)
		(pad "105" smd circle
			(at 4.445 -4.445 90)
			(size 0.635 0.635)
			(layers "F.Cu" "F.Mask" "F.Paste")
			(net "GND")
		)
		(pad "106" smd circle
			(at 4.445 -3.175 90)
			(size 0.635 0.635)
			(layers "F.Cu" "F.Mask" "F.Paste")
			(net "PCIE_T2B_B1_RX_DN<1>")
		)
		(pad "107" smd circle
			(at 4.445 -1.905 90)
			(size 0.635 0.635)
			(layers "F.Cu" "F.Mask" "F.Paste")
			(net "GND")
		)
		(pad "108" smd circle
			(at 4.445 -0.635 90)
			(size 0.635 0.635)
			(layers "F.Cu" "F.Mask" "F.Paste")
			(net "PCIE_T2B_B1_RX_DN<9>")
		)
		(pad "109" smd circle
			(at 4.445 0.635 90)
			(size 0.635 0.635)
			(layers "F.Cu" "F.Mask" "F.Paste")
			(net "GND")
		)
		(pad "110" smd circle
			(at 4.445 1.905 90)
			(size 0.635 0.635)
			(layers "F.Cu" "F.Mask" "F.Paste")
			(net "PCIE_B2T_B1_TX_DN<1>")
		)
		(pad "111" smd circle
			(at 4.445 3.175 90)
			(size 0.635 0.635)
			(layers "F.Cu" "F.Mask" "F.Paste")
			(net "GND")
		)
		(pad "112" smd circle
			(at 4.445 4.445 90)
			(size 0.635 0.635)
			(layers "F.Cu" "F.Mask" "F.Paste")
			(net "PCIE_B2T_B1_TX_DN<9>")
		)
		(pad "113" smd circle
			(at 5.715 -4.445 90)
			(size 0.635 0.635)
			(layers "F.Cu" "F.Mask" "F.Paste")
			(net "PCIE_T2B_B1_RX_DP<0>")
		)
		(pad "114" smd circle
			(at 5.715 -3.175 90)
			(size 0.635 0.635)
			(layers "F.Cu" "F.Mask" "F.Paste")
			(net "GND")
		)
		(pad "115" smd circle
			(at 5.715 -1.905 90)
			(size 0.635 0.635)
			(layers "F.Cu" "F.Mask" "F.Paste")
			(net "PCIE_T2B_B1_RX_DP<8>")
		)
		(pad "116" smd circle
			(at 5.715 -0.635 90)
			(size 0.635 0.635)
			(layers "F.Cu" "F.Mask" "F.Paste")
			(net "GND")
		)
		(pad "117" smd circle
			(at 5.715 0.635 90)
			(size 0.635 0.635)
			(layers "F.Cu" "F.Mask" "F.Paste")
			(net "PCIE_B2T_B1_TX_DP<0>")
		)
		(pad "118" smd circle
			(at 5.715 1.905 90)
			(size 0.635 0.635)
			(layers "F.Cu" "F.Mask" "F.Paste")
			(net "GND")
		)
		(pad "119" smd circle
			(at 5.715 3.175 90)
			(size 0.635 0.635)
			(layers "F.Cu" "F.Mask" "F.Paste")
			(net "PCIE_B2T_B1_TX_DP<8>")
		)
	)
)
